# S9S_MB_2U (Grand Teton) — schematic netlist excerpt (pin names and nets, part order shuffled) for the footprints in the layout excerpt that follows; sources: Cadence DE-HDL packaged netlist, KiCad conversion of 03242023_DA0F0TMBIJ0_F0T_Motherboard_J_brd_V01_OCP.brd

R3026  Q_RES  1K 1% CHIP  pkg 0402LF  page 134 : A = JTAG_BMC_PCH_TCK ; B = GND
R1207  Q_RES  33.2 1% CHIP  pkg 0402LF  page 223 : A = RST_RSMRST_PLD_R_N ; B = RST_RSMRST_PCH_N

(kicad_pcb
	(version 20260206)
	(generator "pcbnew")
	(generator_version "10.0")
	(general
		(thickness 1.6)
		(legacy_teardrops no)
	)
	(paper "A4")
	(title_block
		(title "03242023_DA0F0TMBIJ0_F0T_Motherboard_J_brd_V01_OCP.brd")
		(comment 1 "Grand Teton / footprints 1313-1314 of 6105")
	)
	(layers
		(0 "F.Cu" signal "TOP")
		(4 "In1.Cu" signal "GND")
		(6 "In2.Cu" signal "IN1")
		(8 "In3.Cu" signal "GND1")
		(10 "In4.Cu" signal "IN2")
		(12 "In5.Cu" signal "GND2")
		(14 "In6.Cu" signal "IN3")
		(16 "In7.Cu" signal "GND3")
		(18 "In8.Cu" signal "VCC")
		(20 "In9.Cu" signal "VCC1")
		(22 "In10.Cu" signal "GND4")
		(24 "In11.Cu" signal "IN4")
		(26 "In12.Cu" signal "GND5")
		(28 "In13.Cu" signal "IN5")
		(30 "In14.Cu" signal "GND6")
		(32 "In15.Cu" signal "IN6")
		(34 "In16.Cu" signal "GND7")
		(2 "B.Cu" signal "BOTTOM")
		(9 "F.Adhes" user "F.Adhesive")
		(11 "B.Adhes" user "B.Adhesive")
		(13 "F.Paste" user "Package Geometry/Pastemask Top")
		(15 "B.Paste" user "Package Geometry/Pastemask Bottom")
		(5 "F.SilkS" user "Ref Des/Silkscreen Top")
		(7 "B.SilkS" user "Ref Des/Silkscreen Bottom")
		(1 "F.Mask" user "Board Geometry/Soldermask Top")
		(3 "B.Mask" user "Board Geometry/Soldermask Bottom")
		(17 "Dwgs.User" user "User.Drawings")
		(19 "Cmts.User" user "User.Comments")
		(21 "Eco1.User" user "User.Eco1")
		(23 "Eco2.User" user "User.Eco2")
		(25 "Edge.Cuts" user "Board Geometry/Outline")
		(27 "Margin" user)
		(31 "F.CrtYd" user "Package Geometry/Place Bound Top")
		(29 "B.CrtYd" user "Package Geometry/Place Bound Bottom")
		(35 "F.Fab" user "Ref Des/Assembly Top")
		(33 "B.Fab" user "Ref Des/Assembly Bottom")
	)
	(footprint ""
		(layer "F.Cu")
		(at 109.14888 -54.574948)
		(property "Reference" "R3026"
			(at 0 0 0)
			(layer "F.SilkS")
			(hide yes)
			(effects
				(font
					(size 1.27 1.27)
				)
			)
		)
		(property "Value" ""
			(at 0 0 0)
			(layer "F.Fab")
			(effects
				(font
					(size 1.27 1.27)
				)
			)
		)
		(duplicate_pad_numbers_are_jumpers no)
		(fp_line
			(start -0.7874 -0.4064)
			(end 0.7874 -0.4064)
			(stroke
				(width 0.1524)
				(type default)
			)
			(layer "F.SilkS")
		)
		(fp_line
			(start -0.7874 0.4064)
			(end -0.7874 -0.4064)
			(stroke
				(width 0.1524)
				(type default)
			)
			(layer "F.SilkS")
		)
		(fp_line
			(start 0.7874 -0.4064)
			(end 0.7874 0.4064)
			(stroke
				(width 0.1524)
				(type default)
			)
			(layer "F.SilkS")
		)
		(fp_line
			(start 0.7874 0.4064)
			(end -0.7874 0.4064)
			(stroke
				(width 0.1524)
				(type default)
			)
			(layer "F.SilkS")
		)
		(fp_line
			(start -0.67945 -0.305054)
			(end -0.12065 -0.305054)
			(stroke
				(width 0.1)
				(type default)
			)
			(layer "F.Fab")
		)
		(fp_line
			(start -0.67945 0.3048)
			(end -0.67945 -0.305054)
			(stroke
				(width 0.1)
				(type default)
			)
			(layer "F.Fab")
		)
		(fp_line
			(start -0.12065 -0.305054)
			(end -0.12065 -0.2794)
			(stroke
				(width 0.1)
				(type default)
			)
			(layer "F.Fab")
		)
		(fp_line
			(start -0.12065 -0.2794)
			(end 0.12065 -0.2794)
			(stroke
				(width 0.1)
				(type default)
			)
			(layer "F.Fab")
		)
		(fp_line
			(start -0.12065 0.2794)
			(end -0.12065 0.3048)
			(stroke
				(width 0.1)
				(type default)
			)
			(layer "F.Fab")
		)
		(fp_line
			(start -0.12065 0.3048)
			(end -0.67945 0.3048)
			(stroke
				(width 0.1)
				(type default)
			)
			(layer "F.Fab")
		)
		(fp_line
			(start 0.120396 0.2794)
			(end -0.12065 0.2794)
			(stroke
				(width 0.1)
				(type default)
			)
			(layer "F.Fab")
		)
		(fp_line
			(start 0.120396 0.3048)
			(end 0.120396 0.2794)
			(stroke
				(width 0.1)
				(type default)
			)
			(layer "F.Fab")
		)
		(fp_line
			(start 0.12065 -0.3048)
			(end 0.67945 -0.3048)
			(stroke
				(width 0.1)
				(type default)
			)
			(layer "F.Fab")
		)
		(fp_line
			(start 0.12065 -0.2794)
			(end 0.12065 -0.3048)
			(stroke
				(width 0.1)
				(type default)
			)
			(layer "F.Fab")
		)
		(fp_line
			(start 0.67945 -0.3048)
			(end 0.67945 0.3048)
			(stroke
				(width 0.1)
				(type default)
			)
			(layer "F.Fab")
		)
		(fp_line
			(start 0.67945 0.3048)
			(end 0.120396 0.3048)
			(stroke
				(width 0.1)
				(type default)
			)
			(layer "F.Fab")
		)
		(pad "1" smd circle
			(at -0.40005 0)
			(size 0 0)
			(layers "F.Cu" "F.Mask" "F.Paste")
			(net "JTAG_BMC_PCH_TCK")
		)
		(pad "2" smd circle
			(at 0.40005 0)
			(size 0 0)
			(layers "F.Cu" "F.Mask" "F.Paste")
			(net "GND")
		)
	)
	(footprint ""
		(layer "F.Cu")
		(at 325.61276 -22.675088 90)
		(property "Reference" "R1207"
			(at 0 0 90)
			(layer "F.SilkS")
			(hide yes)
			(effects
				(font
					(size 1.27 1.27)
				)
			)
		)
		(property "Value" ""
			(at 0 0 90)
			(layer "F.Fab")
			(effects
				(font
					(size 1.27 1.27)
				)
			)
		)
		(duplicate_pad_numbers_are_jumpers no)
		(fp_line
			(start 0.7874 -0.4064)
			(end 0.7874 0.4064)
			(stroke
				(width 0.1524)
				(type default)
			)
			(layer "F.SilkS")
		)
		(fp_line
			(start -0.7874 -0.4064)
			(end 0.7874 -0.4064)
			(stroke
				(width 0.1524)
				(type default)
			)
			(layer "F.SilkS")
		)
		(fp_line
			(start 0.7874 0.4064)
			(end -0.7874 0.4064)
			(stroke
				(width 0.1524)
				(type default)
			)
			(layer "F.SilkS")
		)
		(fp_line
			(start -0.7874 0.4064)
			(end -0.7874 -0.4064)
			(stroke
				(width 0.1524)
				(type default)
			)
			(layer "F.SilkS")
		)
		(fp_line
			(start -0.12065 -0.305054)
			(end -0.12065 -0.2794)
			(stroke
				(width 0.1)
				(type default)
			)
			(layer "F.Fab")
		)
		(fp_line
			(start -0.67945 -0.305054)
			(end -0.12065 -0.305054)
			(stroke
				(width 0.1)
				(type default)
			)
			(layer "F.Fab")
		)
		(fp_line
			(start 0.67945 -0.3048)
			(end 0.67945 0.3048)
			(stroke
				(width 0.1)
				(type default)
			)
			(layer "F.Fab")
		)
		(fp_line
			(start 0.12065 -0.3048)
			(end 0.67945 -0.3048)
			(stroke
				(width 0.1)
				(type default)
			)
			(layer "F.Fab")
		)
		(fp_line
			(start 0.12065 -0.2794)
			(end 0.12065 -0.3048)
			(stroke
				(width 0.1)
				(type default)
			)
			(layer "F.Fab")
		)
		(fp_line
			(start -0.12065 -0.2794)
			(end 0.12065 -0.2794)
			(stroke
				(width 0.1)
				(type default)
			)
			(layer "F.Fab")
		)
		(fp_line
			(start 0.120396 0.2794)
			(end -0.12065 0.2794)
			(stroke
				(width 0.1)
				(type default)
			)
			(layer "F.Fab")
		)
		(fp_line
			(start -0.12065 0.2794)
			(end -0.12065 0.3048)
			(stroke
				(width 0.1)
				(type default)
			)
			(layer "F.Fab")
		)
		(fp_line
			(start 0.67945 0.3048)
			(end 0.120396 0.3048)
			(stroke
				(width 0.1)
				(type default)
			)
			(layer "F.Fab")
		)
		(fp_line
			(start 0.120396 0.3048)
			(end 0.120396 0.2794)
			(stroke
				(width 0.1)
				(type default)
			)
			(layer "F.Fab")
		)
		(fp_line
			(start -0.12065 0.3048)
			(end -0.67945 0.3048)
			(stroke
				(width 0.1)
				(type default)
			)
			(layer "F.Fab")
		)
		(fp_line
			(start -0.67945 0.3048)
			(end -0.67945 -0.305054)
			(stroke
				(width 0.1)
				(type default)
			)
			(layer "F.Fab")
		)
		(pad "1" smd circle
			(at -0.40005 0 90)
			(size 0 0)
			(layers "F.Cu" "F.Mask" "F.Paste")
			(net "RST_RSMRST_PLD_R_N")
		)
		(pad "2" smd circle
			(at 0.40005 0 90)
			(size 0 0)
			(layers "F.Cu" "F.Mask" "F.Paste")
			(net "RST_RSMRST_PCH_N")
		)
	)
)
